FILE_TYPE = CONNECTIVITY;
{Allegro Design Entry HDL 16.6-p007 (v16-6-112F) 10/10/2012}
"PAGE_NUMBER" = 201;
0"NC";
1"P3V3_STBY\g";
2"P3V3_STBY\g";
3"P3V3_STBY\g";
4"GND\g";
5"GND\g";
6"PVCCIO_CPU0\g";
7"GND\g";
8"GND\g";
9"GND\g";
10"GND\g";
11"GND\g";
12"GND\g";
13"GND\g";
14"PVCCIO_CPU0\g";
15"VR_FET_SW_P12V_STBY_PVCCIN_CPU0\g";
16"GND\g";
17"GND\g";
18"GND\g";
19"GND\g";
20"SVID_VCLK_PVCCIN_CPU0";
21"IRQ_PVCCIN_CPU0_VRHOT_LVC3_R_N";
22"VR_PVCCIN_CPU0_PWM3"VOLTAGE"3.6";
23"SVID_CLK0_CPU0_R";
24"VR_PVSA_CPU0_BIREF1";
25"ISENSE_PVCCIN_CPU0_PH5_IMON";
26"VR_PVCCIN_CPU0_VREN"VOLTAGE"3.3";
27"SMB_VR_STBY_LVC3_SDA";
28"SMB_VR_STBY_LVC3_SCL";
29"VSENSE_PVCCIN_CPU0_N";
30"VSENSE_PVCCIN_CPU0_AVSP";
31"VSENSE_PVSA_CPU0_BVSP";
32"ISENSE_PVCCIN_CPU0_PH4_IMON";
33"ISENSE_PVCCIN_CPU0_PH3_IMON";
34"ISENSE_PVCCIN_CPU0_PH2_IMON";
35"VR_PVCCIN_CPU0_AIREF5";
36"VR_PVCCIN_CPU0_AIREF4";
37"VR_PVCCIN_CPU0_AIREF3";
38"VR_PVCCIN_CPU0_AIREF1";
39"VR_PVCCIN_CPU0_AIREF2";
40"ISENSE_PVCCIN_CPU0_PH1_IMON";
41"FM_PVCCIN_CPU0_PWR_IN_ALERT_N";
42"VR_PVCCIN_CPU0_VDD"VOLTAGE"3.3";
43"A_TSENSE_PVSA_CPU0";
44"VR_PVCCIN_CPU0_PWM1"VOLTAGE"3.6";
45"IRQ_PVCCIN_CPU0_VRHOT_LVC3_N";
46"PWRGD_PVSA_CPU0_R";
47"VR_PVCCIN_CPU0_VD12";
48"SVID_VALERT_VCCIN_CPU0";
49"PU_VR_PVCCIN_CPU0_IMON";
50"PU_VR_PVCCIN_CPU0_FLT1_SMBALT_N_IMON";
51"SVID_VDIO_PVCCIN_CPU0";
52"PWRGD_PVSA_CPU0";
53"VR_PVSA_CPU0_PWM";
54"VR_VRRDY_PVCCIN_CPU0"VOLTAGE"3.3";
55"A_TSENSE_PVCCIN_CPU0";
56"ISENSE_PVSA_CPU0_IMON";
57"VR_PVCCIN_CPU0_PWM5"VOLTAGE"3.6";
58"VR_PVCCIN_CPU0_PWM4"VOLTAGE"3.6";
59"VR_PVCCIN_CPU0_PWM2"VOLTAGE"3.6";
60"VR_PVCCIN_CPU0_AVINSEN"VOLTAGE"0.8";
61"VR_PVCCIN_CPU0_AVINSEN"VOLTAGE"0.8";
62"SVID_ALERT0_CPU0_R_N";
63"VSENSE_PVCCIN_CPU0_P";
64"PWRGD_PVCCIN_CPU0";
65"VSENSE_PVSA_CPU0_P";
66"SVID_DIO0_CPU0_R";
67"VSENSE_PVSA_CPU0_N";
68"FM_PVCCIN_PVCCSA_CPU0_EN_LVC1";
69"VR_PVCCIN_CPU0_VD12";
70"VR_PVCCIN_CPU0_XADDR1"VOLTAGE"3.3";
71"VR_PVCCIN_CPU0_XADDR2"VOLTAGE"3.3";
%"RES"
"2","(-1100,2000)","0","mstr_discrete","I102";
;
CDS_SEC"1"
LOCATION"R6P32"
VALUE"2.0K"
TOLERANCE"1%"
WATTAGE"1/16W"
PACK_TYPE"0402"
MATERIAL"EMPTY"
PART_NUMBER"G21796-001"
CDS_LIB"mstr_discrete"
ROOM"PVCCIN_CPU0_VR"
CDS_LOCATION"R6P32"
SEC"1"
SEC_TYPE"0402";
"A"
$PN"1"3;
"B"
$PN"2"27;
%"RES"
"2","(-825,2000)","0","mstr_discrete","I103";
;
CDS_SEC"1"
VALUE"2.0K"
LOCATION"R6P37"
TOLERANCE"1%"
MATERIAL"EMPTY"
PART_NUMBER"G21796-001"
PACK_TYPE"0402"
WATTAGE"1/16W"
CDS_LIB"mstr_discrete"
ROOM"PVCCIN_CPU0_VR"
CDS_LOCATION"R6P37"
SEC"1"
SEC_TYPE"0402";
"A"
$PN"1"3;
"B"
$PN"2"28;
%"RES"
"1","(-6675,2525)","0","mstr_discrete","I109";
;
CDS_SEC"1"
PART_NUMBER"G21796-066"
NO_XNET_CONNECTION"1"
PACK_TYPE"0402"
WATTAGE"1/16W"
MATERIAL"CHIP"
TOLERANCE"1%"
VALUE"10.0"
LOCATION"R4E8"
CDS_LIB"mstr_discrete"
ROOM"PVCCIN_CPU0_VR"
CDS_LOCATION"R4E8"
SEC"1"
SEC_TYPE"0402";
"B"
$PN"2"30;
"A"
$PN"1"63;
%"RES"
"1","(-6250,2075)","0","mstr_discrete","I110";
;
CDS_SEC"1"
PART_NUMBER"G21796-066"
PACK_TYPE"0402"
VALUE"10.0"
TOLERANCE"1%"
MATERIAL"CHIP"
WATTAGE"1/16W"
LOCATION"R4D39"
NO_XNET_CONNECTION"1"
CDS_LOCATION"R4D39"
SEC"1"
ROOM"PVCCIN_CPU0_VR"
CDS_LIB"mstr_discrete"
SEC_TYPE"0402";
"B"
$PN"2"31;
"A"
$PN"1"65;
%"RES"
"2","(-3050,4125)","2","mstr_discrete","I111";
;
CDS_SEC"1"
PACK_TYPE"0402"
PART_NUMBER"G21796-026"
LOCATION"R4E3"
VALUE"1.00K"
TOLERANCE"1%"
WATTAGE"1/16W"
MATERIAL"CHIP"
ROOM"PVCCIN_CPU0_VR"
CDS_LOCATION"R4E3"
SEC"1"
SEC_TYPE"0402"
CDS_LIB"mstr_discrete";
"A"
$PN"1"2;
"B"
$PN"2"21;
%"P3V3_STBY"
"1","(-4250,4600)","0","mstr_symbols","I112";
;
VOLTAGE"3.3V"
CDS_LIB"mstr_symbols"
SIZE"1B"
BODY_TYPE"PLUMBING"
HDL_POWER"P3V3_STBY";
"G\NAC"1;
%"P3V3_STBY"
"1","(-3050,4550)","0","mstr_symbols","I113";
;
VOLTAGE"3.3V"
CDS_LIB"mstr_symbols"
SIZE"1B"
BODY_TYPE"PLUMBING"
HDL_POWER"P3V3_STBY";
"G\NAC"2;
%"P3V3_STBY"
"1","(-375,2325)","0","mstr_symbols","I115";
;
SIZE"1B"
CDS_LIB"mstr_symbols"
VOLTAGE"3.3V"
BODY_TYPE"PLUMBING"
HDL_POWER"P3V3_STBY";
"G\NAC"3;
%"RES"
"2","(-1575,4200)","0","mstr_discrete","I116";
;
CDS_SEC"1"
CDS_LOCATION"R4E20"
PART_NUMBER"G21796-311"
TOLERANCE"1.0%"
PACK_TYPE"0402"
LOCATION"R4E20"
MATERIAL"EMPTY"
VALUE"2.26K"
WATTAGE"1/16W"
CDS_LIB"mstr_discrete"
ROOM"PVCCIN_CPU0_VR"
SEC"1"
SEC_TYPE"0402";
"A"
$PN"1"2;
"B"
$PN"2"50;
%"RES"
"2","(-4400,900)","0","mstr_discrete","I120";
;
CDS_SEC"1"
VALUE"4.02K"
TOLERANCE"1%"
MATERIAL"CHIP"
PART_NUMBER"G21796-082"
WATTAGE"1/16W"
LOCATION"R6P27"
PACK_TYPE"0402"
CDS_LIB"mstr_discrete"
ROOM"PVCCIN_CPU0_VR"
CDS_LOCATION"R6P27"
SEC"1"
SEC_TYPE"0402";
"A"
$PN"1"71;
"B"
$PN"2"12;
%"RES"
"2","(-4725,900)","0","mstr_discrete","I121";
;
CDS_SEC"1"
WATTAGE"1/16W"
TOLERANCE"1%"
PART_NUMBER"G21796-082"
MATERIAL"CHIP"
LOCATION"R6P28"
VALUE"4.02K"
PACK_TYPE"0402"
CDS_LIB"mstr_discrete"
SEC_TYPE"0402"
SEC"1"
CDS_LOCATION"R6P28"
ROOM"PVCCIN_CPU0_VR";
"A"
$PN"1"70;
"B"
$PN"2"13;
%"GND"
"1","(-2900,775)","0","mstr_symbols","I123";
;
SIZE"1B"
CDS_LIB"mstr_symbols"
VOLTAGE"0"
BODY_TYPE"PLUMBING"
HDL_POWER"GND";
"A\NAC"4;
%"RES"
"1","(-1125,3325)","0","mstr_discrete","I124";
;
CDS_SEC"1"
WATTAGE"1/16W"
PART_NUMBER"G21796-250"
LOCATION"R4D63"
VALUE"22.1"
PACK_TYPE"0402"
TOLERANCE"1.0%"
MATERIAL"CHIP"
CDS_LIB"mstr_discrete"
ROOM"PVCCIN_CPU0_VR"
CDS_LOCATION"R4D63"
SEC"1"
SEC_TYPE"0402";
"B"
$PN"2"64;
"A"
$PN"1"54;
%"CAP"
"1","(-1450,2075)","0","mstr_discrete","I125";
;
CDS_SEC"1"
VOLTAGE"50V"
LOCATION"C4D42"
VALUE"1000PF"
TOLERANCE"10%"
MATERIAL"X7R"
PACK_TYPE"0402LF"
PART_NUMBER"A36096-046"
CDS_LIB"mstr_discrete"
SEC"1"
CDS_LOCATION"C4D42"
SEC_TYPE"0402LF"
ROOM"PVCCIN_CPU0_VR";
"A"
$PN"1"54;
"B"
$PN"2"5;
%"GND"
"1","(-1450,1850)","0","mstr_symbols","I126";
;
ROOM"PVCCIN_CPU0_VR"
CDS_LIB"mstr_symbols"
VOLTAGE"0"
SIZE"1B"
BODY_TYPE"PLUMBING"
HDL_POWER"GND";
"A\NAC"5;
%"RES"
"1","(-1800,2675)","0","mstr_discrete","I127";
;
CDS_SEC"1"
TOLERANCE"1%"
MATERIAL"CHIP"
PACK_TYPE"0402"
VALUE"33.2"
LOCATION"R4D65"
PART_NUMBER"G21796-074"
WATTAGE"1/16W"
CDS_LOCATION"R4D65"
CDS_LIB"mstr_discrete"
SEC"1"
SEC_TYPE"0402";
"B"
$PN"2"52;
"A"
$PN"1"46;
%"RES"
"1","(-2400,2975)","0","mstr_discrete","I128";
;
CDS_SEC"1"
MATERIAL"CHIP"
TOLERANCE"1%"
PART_NUMBER"G21796-074"
VALUE"33.2"
WATTAGE"1/16W"
LOCATION"R6P45"
PACK_TYPE"0402"
CDS_LOCATION"R6P45"
CDS_LIB"mstr_discrete"
SEC"1"
SEC_TYPE"0402";
"B"
$PN"2"45;
"A"
$PN"1"21;
%"RES"
"1","(-5100,2225)","0","mstr_discrete","I131";
;
CDS_SEC"1"
VALUE"0.0"
LOCATION"R6P18"
TOLERANCE"5%"
WATTAGE"1/16W"
PART_NUMBER"G21497-005"
PACK_TYPE"0402"
MATERIAL"CHIP"
CDS_LOCATION"R6P18"
SEC_TYPE"0402"
SEC"1"
ROOM"PVCCIN_CPU0_VR"
CDS_LIB"mstr_discrete";
"B"
$PN"2"26;
"A"
$PN"1"68;
%"RES"
"2","(-4775,4350)","0","mstr_discrete","I132";
;
CDS_SEC"1"
PART_NUMBER"G21796-026"
PACK_TYPE"0402"
TOLERANCE"1%"
VALUE"1.00K"
MATERIAL"CHIP"
WATTAGE"1/16W"
LOCATION"R6P16"
CDS_LIB"mstr_discrete"
ROOM"BMC"
CDS_LOCATION"R6P16"
BOM_COST"SM_CONTROLLER"
SEC"1"
SEC_TYPE"0402";
"A"
$PN"1"14;
"B"
$PN"2"26;
%"PXE1610B"
"1","(-3800,2575)","0","mstr_controller","I155";
;
PART_NUMBER"H79206-001"
MATERIAL"IC"
LOCATION"EU4D4"
CDS_LOCATION"EU4D4"
PACK_TYPE"QFN"
CDS_SEC"1"
$SEC"1"
CDS_LIB"mstr_controller"
CDS_LMAN_SYM_OUTLINE"-400,900,400,-900";
"VRHOT_N \B"
$PN"13"21;
"THPAD"
$PN"49"9;
"BPWM1"
$PN"1"53;
"APWM1"
$PN"7"44;
"APWM2"
$PN"6"59;
"APWM3"
$PN"5"22;
"APWM4"
$PN"4"58;
"APWM5"
$PN"3"57;
"APWM6"
$PN"2"0;
"SDA"
$PN"8"27;
"SCL"
$PN"9"28;
"VCLK"
$PN"17"20;
"VDIO"
$PN"18"51;
"RESET_N \B"
$PN"10"0;
"AISEN6"
$PN"34"0;
"AIREF6"
$PN"33"0;
"AISEN5"
$PN"32"25;
"AIREF5"
$PN"31"35;
"AISEN4"
$PN"30"32;
"AIREF4"
$PN"29"36;
"XADDR1"
$PN"44"70;
"AISEN3"
$PN"28"33;
"AIREF3"
$PN"27"37;
"XADDR2"
$PN"41"71;
"AISEN2"
$PN"26"34;
"AIREF2"
$PN"25"39;
"ATSEN"
$PN"43"55;
"AISEN1"
$PN"24"40;
"AIREF1"
$PN"23"38;
"VDD"
$PN"47"42;
"BTSEN"
$PN"42"43;
"BISEN1"
$PN"38"56;
"BIREF1"
$PN"37"24;
"PINALRT_N \B"
$PN"14"41;
"VALRT_N \B"
$PN"19"48;
"AVSEN"
$PN"21"30;
"AVREF"
$PN"22"29;
"BVSEN"
$PN"35"31;
"BVREF"
$PN"36"67;
"VINSEN"
$PN"45"61;
"IINSEN"
$PN"46"0;
"VD12"
$PN"48"47;
"AVRRDY"
$PN"11"54;
"AVREN"
$PN"12"26;
"MP0"
$PN"15"46;
"MP1"
$PN"16"0;
"MP2"
$PN"20"50;
"MP3"
$PN"39"49;
"MP4"
$PN"40"0;
%"SC22P50V2JN-4GP"
"1","(-6750,3350)","1","w_hdl","I168";
;
CDS_SEC"1"
$SEC"1"
CDS_LOCATION"CF1"
TYPE"NPO"
RATED"50V"
TOLERANCE"5%"
LOCATION"CF1"
VALUE"SC22P50V2JN-4GP"
PACK_SIZE"0402"
ATTRIBUTE"22PF"
GROUP"POWER_FAIR"
CDS_LIB"w_hdl"
CDS_LMAN_SYM_OUTLINE"-50,25,50,-25"
PACK_TYPE"SMD-BCG"
PART_NUMBER"78.22034.1FL";
"2"
$PN"2"40;
"1"
$PN"1"38;
%"SC22P50V2JN-4GP"
"1","(-6300,3350)","1","w_hdl","I169";
;
CDS_SEC"1"
$SEC"1"
CDS_LOCATION"CF2"
LOCATION"CF2"
PACK_SIZE"0402"
ATTRIBUTE"22PF"
TYPE"NPO"
RATED"50V"
TOLERANCE"5%"
GROUP"POWER_FAIR"
VALUE"SC22P50V2JN-4GP"
CDS_LMAN_SYM_OUTLINE"-50,25,50,-25"
CDS_LIB"w_hdl"
PACK_TYPE"SMD-BCG"
PART_NUMBER"78.22034.1FL";
"2"
$PN"2"34;
"1"
$PN"1"39;
%"SC22P50V2JN-4GP"
"1","(-5825,3350)","1","w_hdl","I170";
;
CDS_SEC"1"
$SEC"1"
CDS_LOCATION"CF3"
GROUP"POWER_FAIR"
LOCATION"CF3"
VALUE"SC22P50V2JN-4GP"
ATTRIBUTE"22PF"
TOLERANCE"5%"
PACK_SIZE"0402"
TYPE"NPO"
RATED"50V"
CDS_LMAN_SYM_OUTLINE"-50,25,50,-25"
CDS_LIB"w_hdl"
PACK_TYPE"SMD-BCG"
PART_NUMBER"78.22034.1FL";
"2"
$PN"2"33;
"1"
$PN"1"37;
%"SC22P50V2JN-4GP"
"1","(-5425,3350)","1","w_hdl","I171";
;
CDS_SEC"1"
$SEC"1"
CDS_LOCATION"CF4"
VALUE"SC22P50V2JN-4GP"
PACK_SIZE"0402"
ATTRIBUTE"22PF"
LOCATION"CF4"
RATED"50V"
TOLERANCE"5%"
GROUP"POWER_FAIR"
TYPE"NPO"
PART_NUMBER"78.22034.1FL"
PACK_TYPE"SMD-BCG"
CDS_LIB"w_hdl"
CDS_LMAN_SYM_OUTLINE"-50,25,50,-25";
"2"
$PN"2"32;
"1"
$PN"1"36;
%"SC22P50V2JN-4GP"
"1","(-5025,3350)","1","w_hdl","I172";
;
CDS_SEC"1"
$SEC"1"
CDS_LOCATION"CF5"
VALUE"SC22P50V2JN-4GP"
GROUP"POWER_FAIR"
LOCATION"CF5"
ATTRIBUTE"22PF"
PACK_SIZE"0402"
TYPE"NPO"
RATED"50V"
TOLERANCE"5%"
CDS_LIB"w_hdl"
CDS_LMAN_SYM_OUTLINE"-50,25,50,-25"
PACK_TYPE"SMD-BCG"
PART_NUMBER"78.22034.1FL";
"2"
$PN"2"25;
"1"
$PN"1"35;
%"SC22P50V2JN-4GP"
"1","(-5800,1325)","1","w_hdl","I173";
;
CDS_SEC"1"
$SEC"1"
CDS_LOCATION"CF6"
PACK_SIZE"0402"
TYPE"NPO"
TOLERANCE"5%"
ATTRIBUTE"22PF"
LOCATION"CF6"
VALUE"SC22P50V2JN-4GP"
RATED"50V"
GROUP"POWER_FAIR"
CDS_LIB"w_hdl"
CDS_LMAN_SYM_OUTLINE"-50,25,50,-25"
PART_NUMBER"78.22034.1FL"
PACK_TYPE"SMD-BCG";
"2"
$PN"2"56;
"1"
$PN"1"24;
%"PVCCIO_CPU0"
"1","(-1275,3950)","0","mstr_symbols","I18";
;
VOLTAGE"1.1V"
CDS_LIB"mstr_symbols"
BODY_TYPE"PLUMBING"
HDL_POWER"PVCCIO_CPU0";
"G\NAC"6;
%"RES"
"1","(-5800,1425)","0","mstr_discrete","I180";
;
CDS_SEC"1"
CDS_LOCATION"RF6"
MATERIAL"CHIP"
WATTAGE"1/16W"
PACK_TYPE"0402"
PART_NUMBER"G85996-004"
TOLERANCE"0.1%"
VALUE"1.0K"
LOCATION"RF6"
GROUP"POWER_FAIR"
ROOM"SB"
CDS_LIB"mstr_discrete"
SEC"1"
SEC_TYPE"0402";
"B"
$PN"2"56;
"A"
$PN"1"24;
%"RES"
"1","(-6750,3500)","0","mstr_discrete","I182";
;
CDS_SEC"1"
CDS_LOCATION"RF1"
FAIR_SS"064.9530D.M001"
TOLERANCE"0.1%"
VALUE"1.0K"
LOCATION"RF1"
PART_NUMBER"G85996-004"
WATTAGE"1/16W"
MATERIAL"CHIP"
PACK_TYPE"0402"
GROUP"POWER_FAIR"
CDS_LIB"mstr_discrete"
ROOM"SB"
SEC"1"
SEC_TYPE"0402";
"B"
$PN"2"40;
"A"
$PN"1"38;
%"RES"
"1","(-6300,3500)","0","mstr_discrete","I183";
;
CDS_SEC"1"
CDS_LOCATION"RF2"
FAIR_SS"064.9530D.M001"
PACK_TYPE"0402"
GROUP"POWER_FAIR"
LOCATION"RF2"
VALUE"1.0K"
TOLERANCE"0.1%"
PART_NUMBER"G85996-004"
WATTAGE"1/16W"
MATERIAL"CHIP"
ROOM"SB"
CDS_LIB"mstr_discrete"
SEC_TYPE"0402"
SEC"1";
"B"
$PN"2"34;
"A"
$PN"1"39;
%"RES"
"1","(-5825,3500)","0","mstr_discrete","I184";
;
CDS_SEC"1"
CDS_LOCATION"RF3"
FAIR_SS"064.9530D.M001"
PACK_TYPE"0402"
MATERIAL"CHIP"
GROUP"POWER_FAIR"
WATTAGE"1/16W"
LOCATION"RF3"
PART_NUMBER"G85996-004"
VALUE"1.0K"
TOLERANCE"0.1%"
CDS_LIB"mstr_discrete"
ROOM"SB"
SEC"1"
SEC_TYPE"0402";
"B"
$PN"2"33;
"A"
$PN"1"37;
%"RES"
"1","(-5425,3500)","0","mstr_discrete","I185";
;
CDS_SEC"1"
CDS_LOCATION"RF4"
FAIR_SS"064.9530D.M001"
LOCATION"RF4"
VALUE"1.0K"
PART_NUMBER"G85996-004"
PACK_TYPE"0402"
TOLERANCE"0.1%"
GROUP"POWER_FAIR"
MATERIAL"CHIP"
WATTAGE"1/16W"
CDS_LIB"mstr_discrete"
ROOM"SB"
SEC"1"
SEC_TYPE"0402";
"B"
$PN"2"32;
"A"
$PN"1"36;
%"RES"
"1","(-5025,3500)","0","mstr_discrete","I186";
;
CDS_SEC"1"
CDS_LOCATION"RF5"
LOCATION"RF5"
PART_NUMBER"G85996-004"
VALUE"1.0K"
WATTAGE"1/16W"
GROUP"POWER_FAIR"
FAIR_SS"064.9530D.M001"
MATERIAL"CHIP"
PACK_TYPE"0402"
TOLERANCE"0.1%"
ROOM"SB"
CDS_LIB"mstr_discrete"
SEC"1"
SEC_TYPE"0402";
"B"
$PN"2"25;
"A"
$PN"1"35;
%"RES"
"2","(-1925,4100)","2","mstr_discrete","I187";
;
CDS_SEC"1"
MATERIAL"CHIP"
WATTAGE"1/16W"
TOLERANCE"1%"
LOCATION"R4E4"
VALUE"1.00K"
PACK_TYPE"0402"
PART_NUMBER"G21796-026"
ROOM"PVCCIN_CPU0_VR"
SEC"1"
SEC_TYPE"0402"
CDS_LIB"mstr_discrete"
CDS_LOCATION"R4E4";
"A"
$PN"1"2;
"B"
$PN"2"41;
%"RES"
"2","(-5650,4275)","0","mstr_discrete","I189";
;
VALUE"49.9"
TOLERANCE"1%"
MATERIAL"EMPTY"
LOCATION"R4E9"
PART_NUMBER"G21796-047"
PACK_TYPE"0402"
WATTAGE"1/16W"
CDS_LOCATION"R4E9"
CDS_SEC"1"
SEC"1"
SEC_TYPE"0402"
ROOM"PVCCIO_CPU0"
CDS_LIB"mstr_discrete";
"A"
$PN"1"14;
"B"
$PN"2"23;
%"RES"
"2","(-1275,3750)","0","mstr_discrete","I190";
;
WATTAGE"1/16W"
MATERIAL"EMPTY"
PART_NUMBER"G21796-017"
PACK_TYPE"0402"
LOCATION"R4E10"
VALUE"100.0"
TOLERANCE"1%"
CDS_LOCATION"R4E10"
CDS_SEC"1"
SEC_TYPE"0402"
SEC"1"
ROOM"PVCCIO_CPU0"
CDS_LIB"mstr_discrete";
"A"
$PN"1"6;
"B"
$PN"2"66;
%"PIN-CON3-27-GP"
"1","(-3225,850)","2","w_hdl","I191";
;
CDS_SEC"1"
CDS_LOCATION"J8D4"
LOCATION"J8D4"
VALUE"PIN-CON3-27-GP"
CDS_LMAN_SYM_OUTLINE"-50,125,50,-125"
CDS_LIB"w_hdl"
PART_NUMBER"021.60545.0103"
SEC_TYPE"CONN-G7"
SEC"1"
PACK_TYPE"CONN-G7";
"3"
$PN"3"28;
"2"
$PN"2"4;
"1"
$PN"1"27;
%"CAP_A"
"1","(-6600,4200)","0","dev_discrete","I192";
;
VOLTAGE"16V"
TOLERANCE"10%"
MATERIAL"X7R"
PACK_TYPE"0402V"
LOCATION"C4D20"
VALUE"0.1UF"
PART_NUMBER"A36096-030"
CDS_SEC"1"
SEC"1"
SEC_TYPE"0402V"
ROOM"CPU_FANS"
BOM_COST"SM_THERM"
CDS_LIB"dev_discrete"
CDS_LOCATION"C4D20";
"B"
$PN"2"17;
"A"
$PN"1"60;
%"RES"
"2","(-2075,3750)","0","mstr_discrete","I22";
;
CDS_SEC"1"
PACK_TYPE"0402"
PART_NUMBER"G21796-311"
WATTAGE"1/16W"
TOLERANCE"1.0%"
VALUE"2.26K"
LOCATION"R4D31"
MATERIAL"EMPTY"
CDS_LIB"mstr_discrete"
ROOM"PVCCIN_CPU0_VR"
CDS_LOCATION"R4D31"
SEC"1"
SEC_TYPE"0402";
"A"
$PN"1"2;
"B"
$PN"2"49;
%"RES"
"2","(-2500,3925)","0","mstr_discrete","I25";
;
CDS_SEC"1"
PACK_TYPE"0402"
PART_NUMBER"G21796-026"
MATERIAL"CHIP"
TOLERANCE"1%"
VALUE"1.00K"
LOCATION"R4D58"
WATTAGE"1/16W"
CDS_LOCATION"R4D58"
CDS_LIB"mstr_discrete"
ROOM"PVCCIN_CPU0_VR"
SEC"1"
SEC_TYPE"0402";
"A"
$PN"1"2;
"B"
$PN"2"54;
%"RES"
"1","(-2025,2875)","0","mstr_discrete","I26";
;
CDS_SEC"1"
MATERIAL"CHIP"
PART_NUMBER"G21497-005"
TOLERANCE"5%"
PACK_TYPE"0402"
VALUE"0.0"
WATTAGE"1/16W"
LOCATION"R4D67"
ROOM"PVCCIN_CPU0_VR"
CDS_LOCATION"R4D67"
SEC"1"
SEC_TYPE"0402"
CDS_LIB"mstr_discrete";
"B"
$PN"2"62;
"A"
$PN"1"48;
%"RES"
"2","(-2775,3925)","2","mstr_discrete","I27";
;
CDS_SEC"1"
LOCATION"R4E5"
PACK_TYPE"0402"
WATTAGE"1/16W"
MATERIAL"CHIP"
PART_NUMBER"G21796-026"
VALUE"1.00K"
TOLERANCE"1%"
ROOM"PVCCIN_CPU0_VR"
SEC"1"
SEC_TYPE"0402"
CDS_LIB"mstr_discrete"
CDS_LOCATION"R4E5";
"A"
$PN"1"2;
"B"
$PN"2"46;
%"GND"
"1","(-1475,800)","0","mstr_symbols","I29";
;
HDL_POWER"GND"
BODY_TYPE"PLUMBING"
VOLTAGE"0"
SIZE"1B"
CDS_LIB"mstr_symbols"
ROOM"PVCCIN_CPU0_VR";
"A\NAC"7;
%"CAP_A"
"1","(-1475,1000)","0","dev_discrete","I30";
;
LOCATION"C4D25"
VALUE"1.0UF"
VOLTAGE"6.3V"
TOLERANCE"10%"
MATERIAL"X6S"
PACK_TYPE"0402V"
PART_NUMBER"D97712-004"
CDS_LIB"dev_discrete"
CDS_LOCATION"C4D25"
CDS_SEC"1"
ROOM"PVCCIN_CPU0_VR"
SEC"1"
SEC_TYPE"0402V";
"B"
$PN"2"7;
"A"
$PN"1"69;
%"CAP_A"
"1","(-1875,1000)","0","dev_discrete","I32";
;
VOLTAGE"16V"
LOCATION"C4D26"
TOLERANCE"10%"
MATERIAL"X7R"
PART_NUMBER"A36096-030"
PACK_TYPE"0402V"
VALUE"0.1UF"
CDS_LIB"dev_discrete"
SEC"1"
SEC_TYPE"0402V"
CDS_SEC"1"
CDS_LOCATION"C4D26"
ROOM"PVCCIN_CPU0_VR";
"B"
$PN"2"8;
"A"
$PN"1"69;
%"GND"
"1","(-1875,800)","0","mstr_symbols","I33";
;
ROOM"PVCCIN_CPU0_VR"
SIZE"1B"
VOLTAGE"0"
CDS_LIB"mstr_symbols"
BODY_TYPE"PLUMBING"
HDL_POWER"GND";
"A\NAC"8;
%"GND"
"1","(-3075,1550)","0","mstr_symbols","I35";
;
ROOM"PVCCIN_CPU0_VR"
VOLTAGE"0"
CDS_LIB"mstr_symbols"
SIZE"1B"
BODY_TYPE"PLUMBING"
HDL_POWER"GND";
"A\NAC"9;
%"GND"
"1","(-3550,3725)","0","mstr_symbols","I36";
;
ROOM"PVCCIN_CPU0_VR"
SIZE"1B"
CDS_LIB"mstr_symbols"
VOLTAGE"0"
BODY_TYPE"PLUMBING"
HDL_POWER"GND";
"A\NAC"10;
%"CAP_A"
"1","(-3550,3925)","0","dev_discrete","I37";
;
VALUE"1.0UF"
LOCATION"C4D15"
TOLERANCE"10%"
VOLTAGE"6.3V"
PACK_TYPE"0402V"
PART_NUMBER"D97712-004"
MATERIAL"X6S"
CDS_LOCATION"C4D15"
CDS_LIB"dev_discrete"
ROOM"PVCCIN_CPU0_VR"
CDS_SEC"1"
SEC"1"
SEC_TYPE"0402V";
"B"
$PN"2"10;
"A"
$PN"1"42;
%"GND"
"1","(-3950,3725)","0","mstr_symbols","I38";
;
ROOM"PVCCIN_CPU0_VR"
VOLTAGE"0"
SIZE"1B"
CDS_LIB"mstr_symbols"
BODY_TYPE"PLUMBING"
HDL_POWER"GND";
"A\NAC"11;
%"CAP_A"
"1","(-3950,3925)","0","dev_discrete","I39";
;
MATERIAL"X7R"
VOLTAGE"16V"
PACK_TYPE"0402V"
TOLERANCE"10%"
LOCATION"C4D19"
VALUE"0.1UF"
PART_NUMBER"A36096-030"
CDS_LOCATION"C4D19"
CDS_LIB"dev_discrete"
CDS_SEC"1"
ROOM"PVCCIN_CPU0_VR"
SEC"1"
SEC_TYPE"0402V";
"B"
$PN"2"11;
"A"
$PN"1"42;
%"RES"
"2","(-4250,4275)","0","mstr_discrete","I40";
;
CDS_SEC"1"
WATTAGE"1/16W"
TOLERANCE"5%"
VALUE"0.0"
MATERIAL"CHIP"
PACK_TYPE"0402"
PART_NUMBER"G21497-005"
LOCATION"R4D26"
CDS_LIB"mstr_discrete"
SEC_TYPE"0402"
SEC"1"
CDS_LOCATION"R4D26"
ROOM"PVCCIN_CPU0_VR";
"A"
$PN"1"1;
"B"
$PN"2"42;
%"GND"
"1","(-4400,575)","0","mstr_symbols","I48";
;
ROOM"PVCCIN_CPU0_VR"
CDS_LIB"mstr_symbols"
VOLTAGE"0"
SIZE"1B"
BODY_TYPE"PLUMBING"
HDL_POWER"GND";
"A\NAC"12;
%"GND"
"1","(-4725,575)","0","mstr_symbols","I50";
;
ROOM"PVCCIN_CPU0_VR"
CDS_LIB"mstr_symbols"
SIZE"1B"
VOLTAGE"0"
BODY_TYPE"PLUMBING"
HDL_POWER"GND";
"A\NAC"13;
%"PVCCIO_CPU0"
"1","(-5325,4825)","0","mstr_symbols","I51";
;
CDS_LIB"mstr_symbols"
VOLTAGE"1.1V"
BODY_TYPE"PLUMBING"
HDL_POWER"PVCCIO_CPU0";
"G\NAC"14;
%"VCC_CORE"
"1","(-6050,4825)","0","mstr_symbols","I53";
;
HDL_POWER"VR_FET_SW_P12V_STBY_PVCCIN_CPU0"
CDS_LIB"mstr_symbols";
"A"15;
%"RES"
"2","(-6050,4625)","0","mstr_discrete","I54";
;
CDS_SEC"1"
PACK_TYPE"0402"
PART_NUMBER"G21796-160"
MATERIAL"CHIP"
WATTAGE"1/16W"
TOLERANCE"1%"
VALUE"100.0K"
LOCATION"R4D27"
CDS_LIB"mstr_discrete"
CDS_LOCATION"R4D27"
ROOM"PVCCIN_CPU0_VR"
SEC"1"
SEC_TYPE"0402";
"A"
$PN"1"15;
"B"
$PN"2"60;
%"RES"
"2","(-6050,4200)","0","mstr_discrete","I55";
;
CDS_SEC"1"
MATERIAL"CHIP"
WATTAGE"1/16W"
TOLERANCE"1%"
VALUE"1.5K"
LOCATION"R4D32"
PACK_TYPE"0402"
PART_NUMBER"G21796-003"
CDS_LIB"mstr_discrete"
CDS_LOCATION"R4D32"
SEC_TYPE"0402"
SEC"1"
ROOM"PVCCIN_CPU0_VR";
"A"
$PN"1"60;
"B"
$PN"2"16;
%"RES"
"1","(-5400,3950)","0","mstr_discrete","I56";
;
CDS_SEC"1"
VALUE"150.0"
MATERIAL"CHIP"
TOLERANCE"1%"
PART_NUMBER"G21796-009"
PACK_TYPE"0402"
LOCATION"R4E6"
WATTAGE"1/16W"
CDS_LIB"mstr_discrete"
CDS_LOCATION"R4E6"
SEC_TYPE"0402"
SEC"1"
ROOM"PVCCIN_CPU0_VR";
"B"
$PN"2"20;
"A"
$PN"1"23;
%"GND"
"1","(-6050,3975)","0","mstr_symbols","I58";
;
CDS_LIB"mstr_symbols"
SIZE"1B"
VOLTAGE"0"
ROOM"PVCCIN_CPU0_VR"
BODY_TYPE"PLUMBING"
HDL_POWER"GND";
"A\NAC"16;
%"GND"
"1","(-6600,4025)","0","mstr_symbols","I61";
;
CDS_LIB"mstr_symbols"
SIZE"1B"
VOLTAGE"0"
ROOM"PVCCIN_CPU0_VR"
BODY_TYPE"PLUMBING"
HDL_POWER"GND";
"A\NAC"17;
%"CAP"
"1","(-5550,2075)","0","mstr_discrete","I64";
;
CDS_SEC"1"
LOCATION"C4D29"
TOLERANCE"10%"
PART_NUMBER"A36096-050"
VALUE"220PF"
MATERIAL"X7R"
VOLTAGE"50V"
PACK_TYPE"0402LF"
ROOM"PVCCIN_CPU0_VR"
CDS_LOCATION"C4D29"
CDS_LIB"mstr_discrete"
SEC"1"
SEC_TYPE"0402LF"
NO_XNET_CONNECTION"1";
"A"
$PN"1"31;
"B"
$PN"2"67;
%"CAP"
"1","(-5425,1275)","0","mstr_discrete","I66";
;
CDS_SEC"1"
TOLERANCE"10%"
VOLTAGE"50V"
VALUE"220PF"
PACK_TYPE"0402LF"
MATERIAL"X7R"
LOCATION"C4D17"
PART_NUMBER"A36096-050"
SEC_TYPE"0402LF"
SEC"1"
CDS_LOCATION"C4D17"
ROOM"PVCCIN_CPU0_VR"
CDS_LIB"mstr_discrete";
"A"
$PN"1"55;
"B"
$PN"2"18;
%"GND"
"1","(-5425,1025)","0","mstr_symbols","I67";
;
HDL_POWER"GND"
BODY_TYPE"PLUMBING"
CDS_LIB"mstr_symbols"
VOLTAGE"0"
ROOM"PVCCIN_CPU0_VR"
SIZE"1B";
"A\NAC"18;
%"CAP"
"1","(-5125,1000)","2","mstr_discrete","I68";
;
CDS_SEC"1"
VALUE"220PF"
VOLTAGE"50V"
PACK_TYPE"0402LF"
LOCATION"C4D18"
TOLERANCE"10%"
PART_NUMBER"A36096-050"
MATERIAL"X7R"
CDS_LIB"mstr_discrete"
SEC_TYPE"0402LF"
CDS_LOCATION"C4D18"
SEC"1"
ROOM"PVCCIN_CPU0_VR";
"A"
$PN"1"43;
"B"
$PN"2"19;
%"GND"
"1","(-5125,775)","0","mstr_symbols","I69";
;
ROOM"PVCCIN_CPU0_VR"
CDS_LIB"mstr_symbols"
VOLTAGE"0"
SIZE"1B"
BODY_TYPE"PLUMBING"
HDL_POWER"GND";
"A\NAC"19;
%"CAP"
"1","(-6450,2375)","0","mstr_discrete","I70";
;
CDS_SEC"1"
PART_NUMBER"A36096-050"
MATERIAL"X7R"
VALUE"220PF"
LOCATION"C4D45"
NO_XNET_CONNECTION"1"
VOLTAGE"50V"
PACK_TYPE"0402LF"
TOLERANCE"10%"
CDS_LIB"mstr_discrete"
CDS_LOCATION"C4D45"
ROOM"PVCCIN_CPU0_VR"
SEC"1"
SEC_TYPE"0402LF";
"A"
$PN"1"30;
"B"
$PN"2"29;
%"RES"
"1","(-2400,2725)","0","mstr_discrete","I98";
;
CDS_SEC"1"
TOLERANCE"5%"
VALUE"0.0"
LOCATION"R4D66"
PACK_TYPE"0402"
MATERIAL"CHIP"
WATTAGE"1/16W"
PART_NUMBER"G21497-005"
CDS_LOCATION"R4D66"
CDS_LIB"mstr_discrete"
SEC_TYPE"0402"
SEC"1"
ROOM"PVCCIN_CPU0_VR";
"B"
$PN"2"66;
"A"
$PN"1"51;
END.
